(kicad_pcb
	(version 20260206)
	(generator "pcbnew")
	(generator_version "10.0")
	(general
		(thickness 1.6)
		(legacy_teardrops no)
	)
	(paper "A4")
	(title_block
		(title "04192023_DAF0TMB3IC0_F0TG_MB_C_brd_V02_OCP.brd")
		(comment 1 "Grand Teton / footprint 2783 of 8354 (U26), pads 1-109 of 6102")
	)
	(layers
		(0 "F.Cu" signal "TOP")
		(4 "In1.Cu" signal "GND")
		(6 "In2.Cu" signal "IN1")
		(8 "In3.Cu" signal "GND1")
		(10 "In4.Cu" signal "IN2")
		(12 "In5.Cu" signal "GND2")
		(14 "In6.Cu" signal "IN3")
		(16 "In7.Cu" signal "GND3")
		(18 "In8.Cu" signal "VCC")
		(20 "In9.Cu" signal "VCC1")
		(22 "In10.Cu" signal "GND4")
		(24 "In11.Cu" signal "IN4")
		(26 "In12.Cu" signal "GND5")
		(28 "In13.Cu" signal "IN5")
		(30 "In14.Cu" signal "GND6")
		(32 "In15.Cu" signal "IN6")
		(34 "In16.Cu" signal "GND7")
		(2 "B.Cu" signal "BOTTOM")
		(9 "F.Adhes" user "F.Adhesive")
		(11 "B.Adhes" user "B.Adhesive")
		(13 "F.Paste" user "Package Geometry/Pastemask Top")
		(15 "B.Paste" user "Package Geometry/Pastemask Bottom")
		(5 "F.SilkS" user "Ref Des/Silkscreen Top")
		(7 "B.SilkS" user "Ref Des/Silkscreen Bottom")
		(1 "F.Mask" user "Board Geometry/Soldermask Top")
		(3 "B.Mask" user "Board Geometry/Soldermask Bottom")
		(17 "Dwgs.User" user "User.Drawings")
		(19 "Cmts.User" user "User.Comments")
		(21 "Eco1.User" user "User.Eco1")
		(23 "Eco2.User" user "User.Eco2")
		(25 "Edge.Cuts" user "Board Geometry/Outline")
		(27 "Margin" user)
		(31 "F.CrtYd" user "Package Geometry/Place Bound Top")
		(29 "B.CrtYd" user "Package Geometry/Place Bound Bottom")
		(35 "F.Fab" user "Ref Des/Assembly Top")
		(33 "B.Fab" user "Ref Des/Assembly Bottom")
	)
	(footprint ""
		(layer "F.Cu")
		(at 111.927894 -258.880356 180)
		(property "Reference" "U26"
			(at -45.05579 -61.794136 0)
			(unlocked yes)
			(layer "F.SilkS")
			(effects
				(font
					(size 0.7874 0.5842)
					(thickness 0.1524)
				)
			)
		)
		(property "Value" ""
			(at 0 0 180)
			(layer "F.Fab")
			(effects
				(font
					(size 1.27 1.27)
				)
			)
		)
		(duplicate_pad_numbers_are_jumpers no)
		(pad "" np_thru_hole circle
			(at -42.099992 0 180)
			(size 4.0132 4.0132)
			(drill 4.0132)
			(layers "*.Cu" "*.Mask")
			(clearance 0.381)
			(thermal_gap 0.381)
		)
		(pad "" np_thru_hole circle
			(at -30.599888 -45.900086 180)
			(size 4.0132 4.0132)
			(drill 4.0132)
			(layers "*.Cu" "*.Mask")
			(clearance 0.381)
			(thermal_gap 0.381)
		)
		(pad "" np_thru_hole circle
			(at -30.599888 45.900086 180)
			(size 4.0132 4.0132)
			(drill 4.0132)
			(layers "*.Cu" "*.Mask")
			(clearance 0.381)
			(thermal_gap 0.381)
		)
		(pad "" np_thru_hole circle
			(at 30.599888 -45.900086 180)
			(size 4.0132 4.0132)
			(drill 4.0132)
			(layers "*.Cu" "*.Mask")
			(clearance 0.381)
			(thermal_gap 0.381)
		)
		(pad "" np_thru_hole circle
			(at 30.599888 45.900086 180)
			(size 4.0132 4.0132)
			(drill 4.0132)
			(layers "*.Cu" "*.Mask")
			(clearance 0.381)
			(thermal_gap 0.381)
		)
		(pad "" np_thru_hole circle
			(at 42.099992 0 180)
			(size 4.0132 4.0132)
			(drill 4.0132)
			(layers "*.Cu" "*.Mask")
			(clearance 0.381)
			(thermal_gap 0.381)
		)
		(pad "A3" smd circle
			(at -32.280098 -36.809934 180)
			(size 0.450088 0.450088)
			(layers "F.Cu" "F.Mask" "F.Paste")
			(net "GND")
		)
		(pad "A4" smd circle
			(at -31.340044 -36.809934 180)
			(size 0.450088 0.450088)
			(layers "F.Cu" "F.Mask" "F.Paste")
			(net "Net_2098")
		)
		(pad "A5" smd circle
			(at -30.39999 -36.809934 180)
			(size 0.450088 0.450088)
			(layers "F.Cu" "F.Mask" "F.Paste")
			(net "I3C_1_SPD_DDRGL_CPU1_R_SDA")
		)
		(pad "A7" smd circle
			(at -28.519882 -36.809934 180)
			(size 0.450088 0.450088)
			(layers "F.Cu" "F.Mask" "F.Paste")
			(net "CLK_100M_CPU1_CLK01_R_DN")
		)
		(pad "A8" smd circle
			(at -27.580082 -36.809934 180)
			(size 0.450088 0.450088)
			(layers "F.Cu" "F.Mask" "F.Paste")
			(net "CLK_100M_CPU1_CLK01_R_DP")
		)
		(pad "A9" smd circle
			(at -26.640028 -36.809934 180)
			(size 0.450088 0.450088)
			(layers "F.Cu" "F.Mask" "F.Paste")
			(net "GND")
		)
		(pad "A10" smd circle
			(at -25.699974 -36.809934 180)
			(size 0.450088 0.450088)
			(layers "F.Cu" "F.Mask" "F.Paste")
			(net "CLK_100M_CPU1_CLK03_R_DP")
		)
		(pad "A11" smd circle
			(at -24.75992 -36.809934 180)
			(size 0.450088 0.450088)
			(layers "F.Cu" "F.Mask" "F.Paste")
			(net "CLK_100M_CPU1_CLK03_R_DN")
		)
		(pad "A13" smd circle
			(at -22.880066 -36.809934 180)
			(size 0.450088 0.450088)
			(layers "F.Cu" "F.Mask" "F.Paste")
			(net "Net_2082")
		)
		(pad "A14" smd circle
			(at -21.940012 -36.809934 180)
			(size 0.450088 0.450088)
			(layers "F.Cu" "F.Mask" "F.Paste")
			(net "Net_2080")
		)
		(pad "A15" smd circle
			(at -20.999958 -36.809934 180)
			(size 0.450088 0.450088)
			(layers "F.Cu" "F.Mask" "F.Paste")
			(net "GND")
		)
		(pad "A16" smd circle
			(at -20.059904 -36.809934 180)
			(size 0.450088 0.450088)
			(layers "F.Cu" "F.Mask" "F.Paste")
			(net "JTAG_CPU1_TMS")
		)
		(pad "A17" smd circle
			(at -19.120104 -36.809934 180)
			(size 0.450088 0.450088)
			(layers "F.Cu" "F.Mask" "F.Paste")
			(net "JTAG_CPU1_TRST_N")
		)
		(pad "A19" smd circle
			(at -17.239996 -36.809934 180)
			(size 0.450088 0.450088)
			(layers "F.Cu" "F.Mask" "F.Paste")
			(net "CLK_100M_REF_IN_DP")
		)
		(pad "A20" smd circle
			(at -16.299942 -36.809934 180)
			(size 0.450088 0.450088)
			(layers "F.Cu" "F.Mask" "F.Paste")
			(net "CLK_100M_REF_IN_DN")
		)
		(pad "A21" smd circle
			(at -15.359888 -36.809934 180)
			(size 0.450088 0.450088)
			(layers "F.Cu" "F.Mask" "F.Paste")
			(net "GND")
		)
		(pad "A22" smd circle
			(at -14.420088 -36.809934 180)
			(size 0.450088 0.450088)
			(layers "F.Cu" "F.Mask" "F.Paste")
			(net "SVID_PVDDCR_CPU0_P1_SVD")
		)
		(pad "A23" smd circle
			(at -13.480034 -36.809934 180)
			(size 0.450088 0.450088)
			(layers "F.Cu" "F.Mask" "F.Paste")
			(net "SVID_PVDDCR_CPU0_P1_SVC")
		)
		(pad "A25" smd circle
			(at -11.599926 -36.809934 180)
			(size 0.450088 0.450088)
			(layers "F.Cu" "F.Mask" "F.Paste")
			(net "NC_CPU1_USB2_USB00_DN")
		)
		(pad "A26" smd circle
			(at -10.659872 -36.809934 180)
			(size 0.450088 0.450088)
			(layers "F.Cu" "F.Mask" "F.Paste")
			(net "NC_CPU1_USB2_USB00_DP")
		)
		(pad "A27" smd circle
			(at -9.720072 -36.809934 180)
			(size 0.450088 0.450088)
			(layers "F.Cu" "F.Mask" "F.Paste")
			(net "GND")
		)
		(pad "A28" smd circle
			(at -8.780018 -36.809934 180)
			(size 0.450088 0.450088)
			(layers "F.Cu" "F.Mask" "F.Paste")
			(net "NC_CPU1_USB2_USB01_DP")
		)
		(pad "A29" smd circle
			(at -7.839964 -36.809934 180)
			(size 0.450088 0.450088)
			(layers "F.Cu" "F.Mask" "F.Paste")
			(net "NC_CPU1_USB2_USB01_DN")
		)
		(pad "A31" smd circle
			(at -5.96011 -36.809934 180)
			(size 0.450088 0.450088)
			(layers "F.Cu" "F.Mask" "F.Paste")
			(net "Net_2121")
		)
		(pad "A32" smd circle
			(at -5.020056 -36.809934 180)
			(size 0.450088 0.450088)
			(layers "F.Cu" "F.Mask" "F.Paste")
			(net "NC_CPU1_AZ_SDOUT")
		)
		(pad "A33" smd circle
			(at -4.080002 -36.809934 180)
			(size 0.450088 0.450088)
			(layers "F.Cu" "F.Mask" "F.Paste")
			(net "NC_CPU1_AZ_SDIN2")
		)
		(pad "A34" smd circle
			(at -3.139948 -36.809934 180)
			(size 0.450088 0.450088)
			(layers "F.Cu" "F.Mask" "F.Paste")
			(net "NC_CPU1_AZ_RST_N")
		)
		(pad "A35" smd circle
			(at -2.199894 -36.809934 180)
			(size 0.450088 0.450088)
			(layers "F.Cu" "F.Mask" "F.Paste")
			(net "Net_2122")
		)
		(pad "A41" smd circle
			(at 2.500122 -36.809934 180)
			(size 0.450088 0.450088)
			(layers "F.Cu" "F.Mask" "F.Paste")
			(net "Net_2123")
		)
		(pad "A42" smd circle
			(at 3.439922 -36.809934 180)
			(size 0.450088 0.450088)
			(layers "F.Cu" "F.Mask" "F.Paste")
			(net "Net_2124")
		)
		(pad "A43" smd circle
			(at 4.379976 -36.809934 180)
			(size 0.450088 0.450088)
			(layers "F.Cu" "F.Mask" "F.Paste")
			(net "GND")
		)
		(pad "A44" smd circle
			(at 5.32003 -36.809934 180)
			(size 0.450088 0.450088)
			(layers "F.Cu" "F.Mask" "F.Paste")
			(net "GND")
		)
		(pad "A45" smd circle
			(at 6.260084 -36.809934 180)
			(size 0.450088 0.450088)
			(layers "F.Cu" "F.Mask" "F.Paste")
			(net "Net_2125")
		)
		(pad "A47" smd circle
			(at 8.139938 -36.809934 180)
			(size 0.450088 0.450088)
			(layers "F.Cu" "F.Mask" "F.Paste")
			(net "GND")
		)
		(pad "A48" smd circle
			(at 9.079992 -36.809934 180)
			(size 0.450088 0.450088)
			(layers "F.Cu" "F.Mask" "F.Paste")
			(net "Net_2126")
		)
		(pad "A49" smd circle
			(at 10.020046 -36.809934 180)
			(size 0.450088 0.450088)
			(layers "F.Cu" "F.Mask" "F.Paste")
			(net "GND")
		)
		(pad "A50" smd circle
			(at 10.9601 -36.809934 180)
			(size 0.450088 0.450088)
			(layers "F.Cu" "F.Mask" "F.Paste")
			(net "Net_2127")
		)
		(pad "A51" smd circle
			(at 11.8999 -36.809934 180)
			(size 0.450088 0.450088)
			(layers "F.Cu" "F.Mask" "F.Paste")
			(net "Net_2128")
		)
		(pad "A53" smd circle
			(at 13.780008 -36.809934 180)
			(size 0.450088 0.450088)
			(layers "F.Cu" "F.Mask" "F.Paste")
			(net "GND")
		)
		(pad "A54" smd circle
			(at 14.720062 -36.809934 180)
			(size 0.450088 0.450088)
			(layers "F.Cu" "F.Mask" "F.Paste")
			(net "Net_2129")
		)
		(pad "A55" smd circle
			(at 15.660116 -36.809934 180)
			(size 0.450088 0.450088)
			(layers "F.Cu" "F.Mask" "F.Paste")
			(net "Net_2130")
		)
		(pad "A56" smd circle
			(at 16.599916 -36.809934 180)
			(size 0.450088 0.450088)
			(layers "F.Cu" "F.Mask" "F.Paste")
			(net "Net_2131")
		)
		(pad "A57" smd circle
			(at 17.53997 -36.809934 180)
			(size 0.450088 0.450088)
			(layers "F.Cu" "F.Mask" "F.Paste")
			(net "Net_2132")
		)
		(pad "A59" smd circle
			(at 19.420078 -36.809934 180)
			(size 0.450088 0.450088)
			(layers "F.Cu" "F.Mask" "F.Paste")
			(net "Net_2133")
		)
		(pad "A60" smd circle
			(at 20.359878 -36.809934 180)
			(size 0.450088 0.450088)
			(layers "F.Cu" "F.Mask" "F.Paste")
			(net "Net_2134")
		)
		(pad "A61" smd circle
			(at 21.299932 -36.809934 180)
			(size 0.450088 0.450088)
			(layers "F.Cu" "F.Mask" "F.Paste")
			(net "GND")
		)
		(pad "A62" smd circle
			(at 22.239986 -36.809934 180)
			(size 0.450088 0.450088)
			(layers "F.Cu" "F.Mask" "F.Paste")
			(net "CPU1_BP3")
		)
		(pad "A63" smd circle
			(at 23.18004 -36.809934 180)
			(size 0.450088 0.450088)
			(layers "F.Cu" "F.Mask" "F.Paste")
			(net "CPU1_BP2")
		)
		(pad "A65" smd circle
			(at 25.059894 -36.809934 180)
			(size 0.450088 0.450088)
			(layers "F.Cu" "F.Mask" "F.Paste")
			(net "CPU1_XTRIG_R2_L7")
		)
		(pad "A66" smd circle
			(at 25.999948 -36.809934 180)
			(size 0.450088 0.450088)
			(layers "F.Cu" "F.Mask" "F.Paste")
			(net "CPU1_XTRIG_R2_L6")
		)
		(pad "A67" smd circle
			(at 26.940002 -36.809934 180)
			(size 0.450088 0.450088)
			(layers "F.Cu" "F.Mask" "F.Paste")
			(net "GND")
		)
		(pad "A68" smd circle
			(at 27.880056 -36.809934 180)
			(size 0.450088 0.450088)
			(layers "F.Cu" "F.Mask" "F.Paste")
			(net "APML_CPU1_ALERT_N")
		)
		(pad "A69" smd circle
			(at 28.82011 -36.809934 180)
			(size 0.450088 0.450088)
			(layers "F.Cu" "F.Mask" "F.Paste")
			(net "CPU1_PROCHOT_N")
		)
		(pad "A71" smd circle
			(at 30.699964 -36.809934 180)
			(size 0.450088 0.450088)
			(layers "F.Cu" "F.Mask" "F.Paste")
			(net "I3C_0_SPD_DDRAF_CPU1_R_SCL")
		)
		(pad "A72" smd circle
			(at 31.640018 -36.809934 180)
			(size 0.450088 0.450088)
			(layers "F.Cu" "F.Mask" "F.Paste")
			(net "GND")
		)
		(pad "A73" smd circle
			(at 32.580072 -36.809934 180)
			(size 0.450088 0.450088)
			(layers "F.Cu" "F.Mask" "F.Paste")
			(net "GND")
		)
		(pad "AA1" smd circle
			(at -34.159952 -20.610068 180)
			(size 0.450088 0.450088)
			(layers "F.Cu" "F.Mask" "F.Paste")
			(net "GND")
		)
		(pad "AA2" smd circle
			(at -33.219898 -20.610068 180)
			(size 0.450088 0.450088)
			(layers "F.Cu" "F.Mask" "F.Paste")
			(net "M_G_CPU1_SA_DQ<20>")
		)
		(pad "AA3" smd circle
			(at -32.280098 -20.610068 180)
			(size 0.450088 0.450088)
			(layers "F.Cu" "F.Mask" "F.Paste")
			(net "M_G_CPU1_SA_DQS_DP<7>")
		)
		(pad "AA4" smd circle
			(at -31.340044 -20.610068 180)
			(size 0.450088 0.450088)
			(layers "F.Cu" "F.Mask" "F.Paste")
			(net "GND")
		)
		(pad "AA5" smd circle
			(at -30.39999 -20.610068 180)
			(size 0.450088 0.450088)
			(layers "F.Cu" "F.Mask" "F.Paste")
			(net "M_K_CPU1_SA_DQ<20>")
		)
		(pad "AA6" smd circle
			(at -29.459936 -20.610068 180)
			(size 0.450088 0.450088)
			(layers "F.Cu" "F.Mask" "F.Paste")
			(net "GND")
		)
		(pad "AA7" smd circle
			(at -28.519882 -20.610068 180)
			(size 0.450088 0.450088)
			(layers "F.Cu" "F.Mask" "F.Paste")
			(net "M_K_CPU1_SA_DQS_DP<7>")
		)
		(pad "AA8" smd circle
			(at -27.580082 -20.610068 180)
			(size 0.450088 0.450088)
			(layers "F.Cu" "F.Mask" "F.Paste")
			(net "GND")
		)
		(pad "AA9" smd circle
			(at -26.640028 -20.610068 180)
			(size 0.450088 0.450088)
			(layers "F.Cu" "F.Mask" "F.Paste")
			(net "M_L_CPU1_SA_DQ<20>")
		)
		(pad "AA10" smd circle
			(at -25.699974 -20.610068 180)
			(size 0.450088 0.450088)
			(layers "F.Cu" "F.Mask" "F.Paste")
			(net "M_L_CPU1_SA_DQS_DP<7>")
		)
		(pad "AA11" smd circle
			(at -24.75992 -20.610068 180)
			(size 0.450088 0.450088)
			(layers "F.Cu" "F.Mask" "F.Paste")
			(net "GND")
		)
		(pad "AA12" smd circle
			(at -23.82012 -20.610068 180)
			(size 0.450088 0.450088)
			(layers "F.Cu" "F.Mask" "F.Paste")
			(net "M_H_CPU1_SA_DQ<20>")
		)
		(pad "AA13" smd circle
			(at -22.880066 -20.610068 180)
			(size 0.450088 0.450088)
			(layers "F.Cu" "F.Mask" "F.Paste")
			(net "GND")
		)
		(pad "AA14" smd circle
			(at -21.940012 -20.610068 180)
			(size 0.450088 0.450088)
			(layers "F.Cu" "F.Mask" "F.Paste")
			(net "M_H_CPU1_SA_DQS_DP<7>")
		)
		(pad "AA15" smd circle
			(at -20.999958 -20.610068 180)
			(size 0.450088 0.450088)
			(layers "F.Cu" "F.Mask" "F.Paste")
			(net "GND")
		)
		(pad "AA16" smd circle
			(at -20.059904 -20.610068 180)
			(size 0.450088 0.450088)
			(layers "F.Cu" "F.Mask" "F.Paste")
			(net "M_J_CPU1_SA_DQ<20>")
		)
		(pad "AA17" smd circle
			(at -19.120104 -20.610068 180)
			(size 0.450088 0.450088)
			(layers "F.Cu" "F.Mask" "F.Paste")
			(net "M_J_CPU1_SA_DQS_DP<7>")
		)
		(pad "AA18" smd circle
			(at -18.18005 -20.610068 180)
			(size 0.450088 0.450088)
			(layers "F.Cu" "F.Mask" "F.Paste")
			(net "GND")
		)
		(pad "AA19" smd circle
			(at -17.239996 -20.610068 180)
			(size 0.450088 0.450088)
			(layers "F.Cu" "F.Mask" "F.Paste")
			(net "M_I_CPU1_SA_DQ<20>")
		)
		(pad "AA20" smd circle
			(at -16.299942 -20.610068 180)
			(size 0.450088 0.450088)
			(layers "F.Cu" "F.Mask" "F.Paste")
			(net "GND")
		)
		(pad "AA21" smd circle
			(at -15.359888 -20.610068 180)
			(size 0.450088 0.450088)
			(layers "F.Cu" "F.Mask" "F.Paste")
			(net "M_I_CPU1_SA_DQS_DP<7>")
		)
		(pad "AA22" smd circle
			(at -14.420088 -20.610068 180)
			(size 0.450088 0.450088)
			(layers "F.Cu" "F.Mask" "F.Paste")
			(net "PVDDCR_SOC_P1")
		)
		(pad "AA23" smd circle
			(at -13.480034 -20.610068 180)
			(size 0.450088 0.450088)
			(layers "F.Cu" "F.Mask" "F.Paste")
			(net "TP_CPU1_TEST6_X3D4")
		)
		(pad "AA24" smd circle
			(at -12.53998 -20.610068 180)
			(size 0.450088 0.450088)
			(layers "F.Cu" "F.Mask" "F.Paste")
			(net "TP_CPU1_TEST5_IOD")
		)
		(pad "AA25" smd circle
			(at -11.599926 -20.610068 180)
			(size 0.450088 0.450088)
			(layers "F.Cu" "F.Mask" "F.Paste")
			(net "TP_CPU1_TEST4_IOD")
		)
		(pad "AA26" smd circle
			(at -10.659872 -20.610068 180)
			(size 0.450088 0.450088)
			(layers "F.Cu" "F.Mask" "F.Paste")
			(net "TP_CPU1_TEST5_CCD7")
		)
		(pad "AA27" smd circle
			(at -9.720072 -20.610068 180)
			(size 0.450088 0.450088)
			(layers "F.Cu" "F.Mask" "F.Paste")
			(net "TP_CPU1_TEST4_CCD7")
		)
		(pad "AA28" smd circle
			(at -8.780018 -20.610068 180)
			(size 0.450088 0.450088)
			(layers "F.Cu" "F.Mask" "F.Paste")
			(net "TP_CPU1_TEST4_CCD11")
		)
		(pad "AA29" smd circle
			(at -7.839964 -20.610068 180)
			(size 0.450088 0.450088)
			(layers "F.Cu" "F.Mask" "F.Paste")
			(net "TP_CPU1_TEST6_X3D2")
		)
		(pad "AA30" smd circle
			(at -6.89991 -20.610068 180)
			(size 0.450088 0.450088)
			(layers "F.Cu" "F.Mask" "F.Paste")
			(net "TP_CPU1_TEST4_CCD3")
		)
		(pad "AA31" smd circle
			(at -5.96011 -20.610068 180)
			(size 0.450088 0.450088)
			(layers "F.Cu" "F.Mask" "F.Paste")
			(net "GND")
		)
		(pad "AA32" smd circle
			(at -5.020056 -20.610068 180)
			(size 0.450088 0.450088)
			(layers "F.Cu" "F.Mask" "F.Paste")
			(net "GMI_CPU0_G0_CPU1_G2_TX_DN<4>")
		)
		(pad "AA33" smd circle
			(at -4.080002 -20.610068 180)
			(size 0.450088 0.450088)
			(layers "F.Cu" "F.Mask" "F.Paste")
			(net "GMI_CPU0_G0_CPU1_G2_TX_DP<4>")
		)
		(pad "AA34" smd circle
			(at -3.139948 -20.610068 180)
			(size 0.450088 0.450088)
			(layers "F.Cu" "F.Mask" "F.Paste")
			(net "GND")
		)
		(pad "AA35" smd circle
			(at -2.199894 -20.610068 180)
			(size 0.450088 0.450088)
			(layers "F.Cu" "F.Mask" "F.Paste")
			(net "GND")
		)
		(pad "AA36" smd circle
			(at -1.260094 -20.610068 180)
			(size 0.450088 0.450088)
			(layers "F.Cu" "F.Mask" "F.Paste")
			(net "GND")
		)
		(pad "AA40" smd circle
			(at 1.560068 -20.610068 180)
			(size 0.450088 0.450088)
			(layers "F.Cu" "F.Mask" "F.Paste")
			(net "GND")
		)
		(pad "AA41" smd circle
			(at 2.500122 -20.610068 180)
			(size 0.450088 0.450088)
			(layers "F.Cu" "F.Mask" "F.Paste")
			(net "GND")
		)
		(pad "AA42" smd circle
			(at 3.439922 -20.610068 180)
			(size 0.450088 0.450088)
			(layers "F.Cu" "F.Mask" "F.Paste")
			(net "GND")
		)
		(pad "AA43" smd circle
			(at 4.379976 -20.610068 180)
			(size 0.450088 0.450088)
			(layers "F.Cu" "F.Mask" "F.Paste")
			(net "GMI_CPU1_G0_CPU0_G2_TX_DP<11>")
		)
		(pad "AA44" smd circle
			(at 5.32003 -20.610068 180)
			(size 0.450088 0.450088)
			(layers "F.Cu" "F.Mask" "F.Paste")
			(net "GMI_CPU1_G0_CPU0_G2_TX_DN<11>")
		)
		(pad "AA45" smd circle
			(at 6.260084 -20.610068 180)
			(size 0.450088 0.450088)
			(layers "F.Cu" "F.Mask" "F.Paste")
			(net "GND")
		)
		(pad "AA46" smd circle
			(at 7.199884 -20.610068 180)
			(size 0.450088 0.450088)
			(layers "F.Cu" "F.Mask" "F.Paste")
			(net "TP_CPU1_TEST6_CCD0")
		)
		(pad "AA47" smd circle
			(at 8.139938 -20.610068 180)
			(size 0.450088 0.450088)
			(layers "F.Cu" "F.Mask" "F.Paste")
			(net "TP_CPU1_TEST6_X3D0")
		)
		(pad "AA48" smd circle
			(at 9.079992 -20.610068 180)
			(size 0.450088 0.450088)
			(layers "F.Cu" "F.Mask" "F.Paste")
			(net "TP_CPU1_TEST4_CCD8")
		)
		(pad "AA49" smd circle
			(at 10.020046 -20.610068 180)
			(size 0.450088 0.450088)
			(layers "F.Cu" "F.Mask" "F.Paste")
			(net "TP_CPU1_TEST6_IOD")
		)
		(pad "AA50" smd circle
			(at 10.9601 -20.610068 180)
			(size 0.450088 0.450088)
			(layers "F.Cu" "F.Mask" "F.Paste")
			(net "TP_CPU1_TEST4_CCD0")
		)
	)
)
